# SCM (Grand Teton) — schematic netlist excerpt (pin names and nets, part order shuffled) for the footprints in the layout excerpt that follows; sources: Cadence DE-HDL packaged netlist, KiCad conversion of 12092022_DA0F0TMDCD0_F0T_Management_Board_D_brd_V3_OCP.brd

D13  Q_LED  IC  pkg THLF  page 49 : A = ID_LED_P3V3_AUX ; C = ID_LED_D_P3V3_AUX
C264  Q_CAP  0.1UF 25V 10% X7R  pkg 0402  page 22 : A = U43_CT ; B = GND

(kicad_pcb
	(version 20260206)
	(generator "pcbnew")
	(generator_version "10.0")
	(general
		(thickness 1.6)
		(legacy_teardrops no)
	)
	(paper "A4")
	(title_block
		(title "12092022_DA0F0TMDCD0_F0T_Management_Board_D_brd_V3_OCP.brd")
		(comment 1 "Grand Teton / footprints 372-373 of 1440")
	)
	(layers
		(0 "F.Cu" signal "TOP")
		(4 "In1.Cu" signal "GND")
		(6 "In2.Cu" signal "IN1")
		(8 "In3.Cu" signal "GND1")
		(10 "In4.Cu" signal "IN2")
		(12 "In5.Cu" signal "VCC")
		(14 "In6.Cu" signal "VCC1")
		(16 "In7.Cu" signal "IN3")
		(18 "In8.Cu" signal "GND2")
		(20 "In9.Cu" signal "IN4")
		(22 "In10.Cu" signal "GND3")
		(2 "B.Cu" signal "BOTTOM")
		(9 "F.Adhes" user "F.Adhesive")
		(11 "B.Adhes" user "B.Adhesive")
		(13 "F.Paste" user "Package Geometry/Pastemask Top")
		(15 "B.Paste" user "Package Geometry/Pastemask Bottom")
		(5 "F.SilkS" user "Ref Des/Silkscreen Top")
		(7 "B.SilkS" user "Ref Des/Silkscreen Bottom")
		(1 "F.Mask" user "Board Geometry/Soldermask Top")
		(3 "B.Mask" user "Board Geometry/Soldermask Bottom")
		(17 "Dwgs.User" user "User.Drawings")
		(19 "Cmts.User" user "User.Comments")
		(21 "Eco1.User" user "User.Eco1")
		(23 "Eco2.User" user "User.Eco2")
		(25 "Edge.Cuts" user "Board Geometry/Outline")
		(27 "Margin" user)
		(31 "F.CrtYd" user "Package Geometry/Place Bound Top")
		(29 "B.CrtYd" user "Package Geometry/Place Bound Bottom")
		(35 "F.Fab" user "Ref Des/Assembly Top")
		(33 "B.Fab" user "Ref Des/Assembly Bottom")
	)
	(footprint ""
		(layer "F.Cu")
		(at 33.782 -44.45 90)
		(property "Reference" "C264"
			(at 0 0 90)
			(layer "F.SilkS")
			(hide yes)
			(effects
				(font
					(size 1.27 1.27)
				)
			)
		)
		(property "Value" ""
			(at 0 0 90)
			(layer "F.Fab")
			(effects
				(font
					(size 1.27 1.27)
				)
			)
		)
		(duplicate_pad_numbers_are_jumpers no)
		(fp_line
			(start 0.7874 -0.4064)
			(end 0.7874 0.4064)
			(stroke
				(width 0.1524)
				(type default)
			)
			(layer "F.SilkS")
		)
		(fp_line
			(start -0.7874 -0.4064)
			(end 0.7874 -0.4064)
			(stroke
				(width 0.1524)
				(type default)
			)
			(layer "F.SilkS")
		)
		(fp_line
			(start 0.7874 0.4064)
			(end -0.7874 0.4064)
			(stroke
				(width 0.1524)
				(type default)
			)
			(layer "F.SilkS")
		)
		(fp_line
			(start -0.7874 0.4064)
			(end -0.7874 -0.4064)
			(stroke
				(width 0.1524)
				(type default)
			)
			(layer "F.SilkS")
		)
		(fp_line
			(start -0.12065 -0.305054)
			(end -0.12065 -0.2794)
			(stroke
				(width 0.1)
				(type default)
			)
			(layer "F.Fab")
		)
		(fp_line
			(start -0.67945 -0.305054)
			(end -0.12065 -0.305054)
			(stroke
				(width 0.1)
				(type default)
			)
			(layer "F.Fab")
		)
		(fp_line
			(start 0.67945 -0.3048)
			(end 0.67945 0.3048)
			(stroke
				(width 0.1)
				(type default)
			)
			(layer "F.Fab")
		)
		(fp_line
			(start 0.12065 -0.3048)
			(end 0.67945 -0.3048)
			(stroke
				(width 0.1)
				(type default)
			)
			(layer "F.Fab")
		)
		(fp_line
			(start 0.12065 -0.2794)
			(end 0.12065 -0.3048)
			(stroke
				(width 0.1)
				(type default)
			)
			(layer "F.Fab")
		)
		(fp_line
			(start -0.12065 -0.2794)
			(end 0.12065 -0.2794)
			(stroke
				(width 0.1)
				(type default)
			)
			(layer "F.Fab")
		)
		(fp_line
			(start 0.120396 0.2794)
			(end -0.12065 0.2794)
			(stroke
				(width 0.1)
				(type default)
			)
			(layer "F.Fab")
		)
		(fp_line
			(start -0.12065 0.2794)
			(end -0.12065 0.3048)
			(stroke
				(width 0.1)
				(type default)
			)
			(layer "F.Fab")
		)
		(fp_line
			(start 0.67945 0.3048)
			(end 0.120396 0.3048)
			(stroke
				(width 0.1)
				(type default)
			)
			(layer "F.Fab")
		)
		(fp_line
			(start 0.120396 0.3048)
			(end 0.120396 0.2794)
			(stroke
				(width 0.1)
				(type default)
			)
			(layer "F.Fab")
		)
		(fp_line
			(start -0.12065 0.3048)
			(end -0.67945 0.3048)
			(stroke
				(width 0.1)
				(type default)
			)
			(layer "F.Fab")
		)
		(fp_line
			(start -0.67945 0.3048)
			(end -0.67945 -0.305054)
			(stroke
				(width 0.1)
				(type default)
			)
			(layer "F.Fab")
		)
		(pad "1" smd circle
			(at -0.40005 0 90)
			(size 0 0)
			(layers "F.Cu" "F.Mask" "F.Paste")
			(net "U43_CT")
		)
		(pad "2" smd circle
			(at 0.40005 0 90)
			(size 0 0)
			(layers "F.Cu" "F.Mask" "F.Paste")
			(net "GND")
		)
	)
	(footprint ""
		(layer "F.Cu")
		(at 29.729938 -6.290056)
		(property "Reference" "D13"
			(at 1.512062 -2.624074 0)
			(unlocked yes)
			(layer "F.SilkS")
			(effects
				(font
					(size 0.7874 0.5842)
					(thickness 0.1524)
				)
				(justify left)
			)
		)
		(property "Value" ""
			(at 0 0 0)
			(layer "F.Fab")
			(effects
				(font
					(size 1.27 1.27)
				)
			)
		)
		(duplicate_pad_numbers_are_jumpers no)
		(fp_line
			(start -0.979932 -2.100072)
			(end 3.519932 -2.100072)
			(stroke
				(width 0.1524)
				(type default)
			)
			(layer "F.SilkS")
		)
		(fp_line
			(start -0.979932 3.899916)
			(end -0.979932 -2.100072)
			(stroke
				(width 0.1524)
				(type default)
			)
			(layer "F.SilkS")
		)
		(fp_line
			(start -0.130048 3.899916)
			(end -0.979932 3.899916)
			(stroke
				(width 0.1524)
				(type default)
			)
			(layer "F.SilkS")
		)
		(fp_line
			(start -0.130048 4.800092)
			(end -0.130048 3.899916)
			(stroke
				(width 0.1524)
				(type default)
			)
			(layer "F.SilkS")
		)
		(fp_line
			(start 2.670048 3.899916)
			(end 2.670048 4.800092)
			(stroke
				(width 0.1524)
				(type default)
			)
			(layer "F.SilkS")
		)
		(fp_line
			(start 3.519932 -2.100072)
			(end 3.519932 3.899916)
			(stroke
				(width 0.1524)
				(type default)
			)
			(layer "F.SilkS")
		)
		(fp_line
			(start 3.519932 3.899916)
			(end 2.670048 3.899916)
			(stroke
				(width 0.1524)
				(type default)
			)
			(layer "F.SilkS")
		)
		(fp_arc
			(start 1.27 6.199886)
			(mid 0.280106 5.789911)
			(end -0.130048 4.800092)
			(stroke
				(width 0.1524)
				(type default)
			)
			(layer "F.SilkS")
		)
		(fp_arc
			(start 2.670048 4.800092)
			(mid 2.259894 5.789911)
			(end 1.27 6.199886)
			(stroke
				(width 0.1524)
				(type default)
			)
			(layer "F.SilkS")
		)
		(fp_line
			(start -0.979932 -2.100072)
			(end 3.519932 -2.100072)
			(stroke
				(width 0.1)
				(type default)
			)
			(layer "F.Fab")
		)
		(fp_line
			(start -0.979932 3.899916)
			(end -0.979932 -2.100072)
			(stroke
				(width 0.1)
				(type default)
			)
			(layer "F.Fab")
		)
		(fp_line
			(start -0.130048 3.899916)
			(end -0.979932 3.899916)
			(stroke
				(width 0.1)
				(type default)
			)
			(layer "F.Fab")
		)
		(fp_line
			(start -0.130048 4.800092)
			(end -0.130048 3.899916)
			(stroke
				(width 0.1)
				(type default)
			)
			(layer "F.Fab")
		)
		(fp_line
			(start 2.670048 3.899916)
			(end 2.670048 4.800092)
			(stroke
				(width 0.1)
				(type default)
			)
			(layer "F.Fab")
		)
		(fp_line
			(start 3.519932 -2.100072)
			(end 3.519932 3.899916)
			(stroke
				(width 0.1)
				(type default)
			)
			(layer "F.Fab")
		)
		(fp_line
			(start 3.519932 3.899916)
			(end 2.670048 3.899916)
			(stroke
				(width 0.1)
				(type default)
			)
			(layer "F.Fab")
		)
		(fp_arc
			(start 1.27 6.199886)
			(mid 0.280106 5.789911)
			(end -0.130048 4.800092)
			(stroke
				(width 0.1)
				(type default)
			)
			(layer "F.Fab")
		)
		(fp_arc
			(start 2.670048 4.800092)
			(mid 2.259894 5.789911)
			(end 1.27 6.199886)
			(stroke
				(width 0.1)
				(type default)
			)
			(layer "F.Fab")
		)
		(pad "A" thru_hole rect
			(at 0 0)
			(size 1.2192 1.2192)
			(drill 0.8128)
			(layers "*.Cu" "*.Mask")
			(remove_unused_layers no)
			(net "ID_LED_P3V3_AUX")
			(clearance 0.0508)
			(thermal_gap 0.0508)
			(padstack
				(mode front_inner_back)
				(layer "Inner"
					(shape circle)
					(size 1.2192 1.2192)
					(clearance 0.0508)
				)
				(layer "B.Cu"
					(shape rect)
					(size 1.2192 1.2192)
					(clearance 0.0508)
				)
			)
		)
		(pad "C" thru_hole circle
			(at 2.54 0)
			(size 1.2192 1.2192)
			(drill 0.8128)
			(layers "*.Cu" "*.Mask")
			(remove_unused_layers no)
			(net "ID_LED_D_P3V3_AUX")
			(clearance 0.0508)
			(thermal_gap 0.0508)
		)
	)
)
